(kicad_pcb
	(version 20260206)
	(generator "pcbnew")
	(generator_version "10.0")
	(general
		(thickness 1.6)
		(legacy_teardrops no)
	)
	(paper "A4")
	(title_block
		(title "Wiwynn_Tioga_Pass_MB.brd")
		(comment 1 "Tioga Pass / footprint 1357 of 4770 (J1C1), pads 1-72 of 76")
	)
	(layers
		(0 "F.Cu" signal "TOP")
		(4 "In1.Cu" signal "L2GND")
		(6 "In2.Cu" signal "L3")
		(8 "In3.Cu" signal "L4GND")
		(10 "In4.Cu" signal "L5")
		(12 "In5.Cu" signal "L6GND")
		(14 "In6.Cu" signal "L7VCC")
		(16 "In7.Cu" signal "L8VCC")
		(18 "In8.Cu" signal "L9GND")
		(20 "In9.Cu" signal "L10")
		(22 "In10.Cu" signal "L11GND")
		(24 "In11.Cu" signal "L12")
		(26 "In12.Cu" signal "L13GND")
		(2 "B.Cu" signal "BOTTOM")
		(9 "F.Adhes" user "F.Adhesive")
		(11 "B.Adhes" user "B.Adhesive")
		(13 "F.Paste" user "Package Geometry/Pastemask Top")
		(15 "B.Paste" user "Package Geometry/Pastemask Bottom")
		(5 "F.SilkS" user "Ref Des/Silkscreen Top")
		(7 "B.SilkS" user "Ref Des/Silkscreen Bottom")
		(1 "F.Mask" user "Board Geometry/Soldermask Top")
		(3 "B.Mask" user "Board Geometry/Soldermask Bottom")
		(17 "Dwgs.User" user "User.Drawings")
		(19 "Cmts.User" user "User.Comments")
		(21 "Eco1.User" user "User.Eco1")
		(23 "Eco2.User" user "User.Eco2")
		(25 "Edge.Cuts" user "Board Geometry/Outline")
		(27 "Margin" user)
		(31 "F.CrtYd" user "Package Geometry/Place Bound Top")
		(29 "B.CrtYd" user "Package Geometry/Place Bound Bottom")
		(35 "F.Fab" user "Ref Des/Assembly Top")
		(33 "B.Fab" user "Ref Des/Assembly Bottom")
	)
	(footprint ""
		(layer "F.Cu")
		(at 2.29997 -97.769934 -90)
		(property "Reference" "J1C1"
			(at 0 0 270)
			(layer "F.SilkS")
			(hide yes)
			(effects
				(font
					(size 1.27 1.27)
				)
			)
		)
		(property "Value" "*"
			(at -20.8026 -3.4036 270)
			(unlocked yes)
			(layer "F.Fab")
			(hide yes)
			(effects
				(font
					(size 1.27 1.016)
					(thickness 0.1524)
				)
			)
		)
		(property "Device Type" "DM-FCI-CONN76-8R-GP-U-01_CONN-A"
			(at -20.8026 -4.9276 270)
			(unlocked yes)
			(layer "F.Fab")
			(hide yes)
			(effects
				(font
					(size 1.27 1.016)
					(thickness 0.1524)
				)
			)
		)
		(duplicate_pad_numbers_are_jumpers no)
		(pad "A1" thru_hole circle
			(at -6.999986 6.199886 270)
			(size 0.8128 0.8128)
			(drill 0.399796)
			(layers "*.Cu" "*.Mask")
			(remove_unused_layers no)
			(net "P3E_CPU1_PE3_MP_RXN<8>")
			(clearance 0.2921)
			(thermal_gap 0.2921)
		)
		(pad "A2" thru_hole circle
			(at -4.99999 6.299962 270)
			(size 0.8636 0.8636)
			(drill 0.499872)
			(layers "*.Cu" "*.Mask")
			(remove_unused_layers no)
			(net "GND")
			(clearance 0.1778)
			(thermal_gap 0.1778)
		)
		(pad "A3" thru_hole circle
			(at -2.999994 6.199886 270)
			(size 0.8128 0.8128)
			(drill 0.399796)
			(layers "*.Cu" "*.Mask")
			(remove_unused_layers no)
			(net "P3E_CPU1_PE3_MP_RXP<14>")
			(clearance 0.2921)
			(thermal_gap 0.2921)
		)
		(pad "A4" thru_hole circle
			(at -0.999998 6.299962 270)
			(size 0.8636 0.8636)
			(drill 0.499872)
			(layers "*.Cu" "*.Mask")
			(remove_unused_layers no)
			(net "GND")
			(clearance 0.1778)
			(thermal_gap 0.1778)
		)
		(pad "A5" thru_hole circle
			(at 0.999998 6.199886 270)
			(size 0.8128 0.8128)
			(drill 0.399796)
			(layers "*.Cu" "*.Mask")
			(remove_unused_layers no)
			(net "TP_IOA5")
			(clearance 0.2921)
			(thermal_gap 0.2921)
		)
		(pad "A6" thru_hole circle
			(at 2.999994 6.299962 270)
			(size 0.8636 0.8636)
			(drill 0.499872)
			(layers "*.Cu" "*.Mask")
			(remove_unused_layers no)
			(net "GND")
			(clearance 0.1778)
			(thermal_gap 0.1778)
		)
		(pad "A7" thru_hole circle
			(at 4.99999 6.199886 270)
			(size 0.8128 0.8128)
			(drill 0.399796)
			(layers "*.Cu" "*.Mask")
			(remove_unused_layers no)
			(net "P3E_CPU1_PE3_MP_C_TXN<11>")
			(clearance 0.2921)
			(thermal_gap 0.2921)
		)
		(pad "A8" thru_hole circle
			(at 6.999986 6.299962 270)
			(size 0.8636 0.8636)
			(drill 0.499872)
			(layers "*.Cu" "*.Mask")
			(remove_unused_layers no)
			(net "GND")
			(clearance 0.1778)
			(thermal_gap 0.1778)
		)
		(pad "B1" thru_hole circle
			(at -6.999986 4.800092 270)
			(size 0.8128 0.8128)
			(drill 0.399796)
			(layers "*.Cu" "*.Mask")
			(remove_unused_layers no)
			(net "P3E_CPU1_PE3_MP_RXP<8>")
			(clearance 0.2921)
			(thermal_gap 0.2921)
		)
		(pad "B2" thru_hole circle
			(at -4.99999 4.899914 270)
			(size 0.8128 0.8128)
			(drill 0.399796)
			(layers "*.Cu" "*.Mask")
			(remove_unused_layers no)
			(net "P3E_CPU1_PE3_MP_RXN<11>")
			(clearance 0.2921)
			(thermal_gap 0.2921)
		)
		(pad "B3" thru_hole circle
			(at -2.999994 4.800092 270)
			(size 0.8128 0.8128)
			(drill 0.399796)
			(layers "*.Cu" "*.Mask")
			(remove_unused_layers no)
			(net "P3E_CPU1_PE3_MP_RXN<14>")
			(clearance 0.2921)
			(thermal_gap 0.2921)
		)
		(pad "B4" thru_hole circle
			(at -0.999998 4.899914 270)
			(size 0.8128 0.8128)
			(drill 0.399796)
			(layers "*.Cu" "*.Mask")
			(remove_unused_layers no)
			(net "TP_FM_WAKE_N")
			(clearance 0.1524)
			(thermal_gap 0.1524)
		)
		(pad "B5" thru_hole circle
			(at 0.999998 4.800092 270)
			(size 0.8128 0.8128)
			(drill 0.399796)
			(layers "*.Cu" "*.Mask")
			(remove_unused_layers no)
			(net "IRQ_BOARD_BMC_ALERT_N")
			(clearance 0.2921)
			(thermal_gap 0.2921)
		)
		(pad "B6" thru_hole circle
			(at 2.999994 4.899914 270)
			(size 0.8128 0.8128)
			(drill 0.399796)
			(layers "*.Cu" "*.Mask")
			(remove_unused_layers no)
			(net "SMB_PEHPCPU1_STBY_LVC3_SDA")
			(clearance 0.1524)
			(thermal_gap 0.1524)
		)
		(pad "B7" thru_hole circle
			(at 4.99999 4.800092 270)
			(size 0.8128 0.8128)
			(drill 0.399796)
			(layers "*.Cu" "*.Mask")
			(remove_unused_layers no)
			(net "P3E_CPU1_PE3_MP_C_TXP<11>")
			(clearance 0.2921)
			(thermal_gap 0.2921)
		)
		(pad "B8" thru_hole circle
			(at 6.999986 4.899914 270)
			(size 0.8128 0.8128)
			(drill 0.399796)
			(layers "*.Cu" "*.Mask")
			(remove_unused_layers no)
			(net "P3E_CPU1_PE3_MP_C_TXN<8>")
			(clearance 0.2921)
			(thermal_gap 0.2921)
		)
		(pad "C1" thru_hole circle
			(at -6.999986 3.400044 270)
			(size 0.8636 0.8636)
			(drill 0.499872)
			(layers "*.Cu" "*.Mask")
			(remove_unused_layers no)
			(net "GND")
			(clearance 0.1778)
			(thermal_gap 0.1778)
		)
		(pad "C2" thru_hole circle
			(at -4.99999 3.50012 270)
			(size 0.8128 0.8128)
			(drill 0.399796)
			(layers "*.Cu" "*.Mask")
			(remove_unused_layers no)
			(net "P3E_CPU1_PE3_MP_RXP<11>")
			(clearance 0.2921)
			(thermal_gap 0.2921)
		)
		(pad "C3" thru_hole circle
			(at -2.999994 3.400044 270)
			(size 0.8636 0.8636)
			(drill 0.499872)
			(layers "*.Cu" "*.Mask")
			(remove_unused_layers no)
			(net "GND")
			(clearance 0.1778)
			(thermal_gap 0.1778)
		)
		(pad "C4" thru_hole circle
			(at -0.999998 3.50012 270)
			(size 0.8128 0.8128)
			(drill 0.399796)
			(layers "*.Cu" "*.Mask")
			(remove_unused_layers no)
			(net "FM_BB_BMC_MP_GPIO")
			(clearance 0.1524)
			(thermal_gap 0.1524)
		)
		(pad "C5" thru_hole circle
			(at 0.999998 3.400044 270)
			(size 0.8636 0.8636)
			(drill 0.499872)
			(layers "*.Cu" "*.Mask")
			(remove_unused_layers no)
			(net "GND")
			(clearance 0.1778)
			(thermal_gap 0.1778)
		)
		(pad "C6" thru_hole circle
			(at 2.999994 3.50012 270)
			(size 0.8128 0.8128)
			(drill 0.399796)
			(layers "*.Cu" "*.Mask")
			(remove_unused_layers no)
			(net "SMB_PEHPCPU1_STBY_LVC3_SCL")
			(clearance 0.1524)
			(thermal_gap 0.1524)
		)
		(pad "C7" thru_hole circle
			(at 4.99999 3.400044 270)
			(size 0.8636 0.8636)
			(drill 0.499872)
			(layers "*.Cu" "*.Mask")
			(remove_unused_layers no)
			(net "GND")
			(clearance 0.1778)
			(thermal_gap 0.1778)
		)
		(pad "C8" thru_hole circle
			(at 6.999986 3.50012 270)
			(size 0.8128 0.8128)
			(drill 0.399796)
			(layers "*.Cu" "*.Mask")
			(remove_unused_layers no)
			(net "P3E_CPU1_PE3_MP_C_TXP<8>")
			(clearance 0.2921)
			(thermal_gap 0.2921)
		)
		(pad "D1" thru_hole circle
			(at -6.999986 1.999996 270)
			(size 0.8128 0.8128)
			(drill 0.399796)
			(layers "*.Cu" "*.Mask")
			(remove_unused_layers no)
			(net "P3E_CPU1_PE3_MP_RXN<9>")
			(clearance 0.2921)
			(thermal_gap 0.2921)
		)
		(pad "D2" thru_hole circle
			(at -4.99999 2.100072 270)
			(size 0.8636 0.8636)
			(drill 0.499872)
			(layers "*.Cu" "*.Mask")
			(remove_unused_layers no)
			(net "GND")
			(clearance 0.1778)
			(thermal_gap 0.1778)
		)
		(pad "D3" thru_hole circle
			(at -2.999994 1.999996 270)
			(size 0.8128 0.8128)
			(drill 0.399796)
			(layers "*.Cu" "*.Mask")
			(remove_unused_layers no)
			(net "P3E_CPU1_PE3_MP_RXN<15>")
			(clearance 0.2921)
			(thermal_gap 0.2921)
		)
		(pad "D4" thru_hole circle
			(at -0.999998 2.100072 270)
			(size 0.8636 0.8636)
			(drill 0.499872)
			(layers "*.Cu" "*.Mask")
			(remove_unused_layers no)
			(net "GND")
			(clearance 0.1778)
			(thermal_gap 0.1778)
		)
		(pad "D5" thru_hole circle
			(at 0.999998 1.999996 270)
			(size 0.8128 0.8128)
			(drill 0.399796)
			(layers "*.Cu" "*.Mask")
			(remove_unused_layers no)
			(net "SMB_LAN_STBY_LVC3_SDA")
			(clearance 0.2921)
			(thermal_gap 0.2921)
		)
		(pad "D6" thru_hole circle
			(at 2.999994 2.100072 270)
			(size 0.8636 0.8636)
			(drill 0.499872)
			(layers "*.Cu" "*.Mask")
			(remove_unused_layers no)
			(net "GND")
			(clearance 0.1778)
			(thermal_gap 0.1778)
		)
		(pad "D7" thru_hole circle
			(at 4.99999 1.999996 270)
			(size 0.8128 0.8128)
			(drill 0.399796)
			(layers "*.Cu" "*.Mask")
			(remove_unused_layers no)
			(net "P3E_CPU1_PE3_MP_C_TXN<12>")
			(clearance 0.2921)
			(thermal_gap 0.2921)
		)
		(pad "D8" thru_hole circle
			(at 6.999986 2.100072 270)
			(size 0.8636 0.8636)
			(drill 0.499872)
			(layers "*.Cu" "*.Mask")
			(remove_unused_layers no)
			(net "GND")
			(clearance 0.1778)
			(thermal_gap 0.1778)
		)
		(pad "E1" thru_hole circle
			(at -6.999986 0.599948 270)
			(size 0.8128 0.8128)
			(drill 0.399796)
			(layers "*.Cu" "*.Mask")
			(remove_unused_layers no)
			(net "P3E_CPU1_PE3_MP_RXP<9>")
			(clearance 0.2921)
			(thermal_gap 0.2921)
		)
		(pad "E2" thru_hole circle
			(at -4.99999 0.700024 270)
			(size 0.8128 0.8128)
			(drill 0.399796)
			(layers "*.Cu" "*.Mask")
			(remove_unused_layers no)
			(net "P3E_CPU1_PE3_MP_RXN<12>")
			(clearance 0.2921)
			(thermal_gap 0.2921)
		)
		(pad "E3" thru_hole circle
			(at -2.999994 0.599948 270)
			(size 0.8128 0.8128)
			(drill 0.399796)
			(layers "*.Cu" "*.Mask")
			(remove_unused_layers no)
			(net "P3E_CPU1_PE3_MP_RXP<15>")
			(clearance 0.2921)
			(thermal_gap 0.2921)
		)
		(pad "E4" thru_hole circle
			(at -0.999998 0.700024 270)
			(size 0.8128 0.8128)
			(drill 0.399796)
			(layers "*.Cu" "*.Mask")
			(remove_unused_layers no)
			(net "TP_IOE4")
			(clearance 0.1524)
			(thermal_gap 0.1524)
		)
		(pad "E5" thru_hole circle
			(at 0.999998 0.599948 270)
			(size 0.8128 0.8128)
			(drill 0.399796)
			(layers "*.Cu" "*.Mask")
			(remove_unused_layers no)
			(net "SMB_LAN_STBY_LVC3_SCL")
			(clearance 0.2921)
			(thermal_gap 0.2921)
		)
		(pad "E6" thru_hole circle
			(at 2.999994 0.700024 270)
			(size 0.8128 0.8128)
			(drill 0.399796)
			(layers "*.Cu" "*.Mask")
			(remove_unused_layers no)
			(net "P3E_CPU1_PE3_MP_C_TXN<14>")
			(clearance 0.2921)
			(thermal_gap 0.2921)
		)
		(pad "E7" thru_hole circle
			(at 4.99999 0.599948 270)
			(size 0.8128 0.8128)
			(drill 0.399796)
			(layers "*.Cu" "*.Mask")
			(remove_unused_layers no)
			(net "P3E_CPU1_PE3_MP_C_TXP<12>")
			(clearance 0.2921)
			(thermal_gap 0.2921)
		)
		(pad "E8" thru_hole circle
			(at 6.999986 0.700024 270)
			(size 0.8128 0.8128)
			(drill 0.399796)
			(layers "*.Cu" "*.Mask")
			(remove_unused_layers no)
			(net "P3E_CPU1_PE3_MP_C_TXN<9>")
			(clearance 0.2921)
			(thermal_gap 0.2921)
		)
		(pad "F1" thru_hole circle
			(at -6.999986 -0.8001 270)
			(size 0.8636 0.8636)
			(drill 0.499872)
			(layers "*.Cu" "*.Mask")
			(remove_unused_layers no)
			(net "GND")
			(clearance 0.1778)
			(thermal_gap 0.1778)
		)
		(pad "F2" thru_hole circle
			(at -4.99999 -0.700024 270)
			(size 0.8128 0.8128)
			(drill 0.399796)
			(layers "*.Cu" "*.Mask")
			(remove_unused_layers no)
			(net "P3E_CPU1_PE3_MP_RXP<12>")
			(clearance 0.2921)
			(thermal_gap 0.2921)
		)
		(pad "F3" thru_hole circle
			(at -2.999994 -0.8001 270)
			(size 0.8636 0.8636)
			(drill 0.499872)
			(layers "*.Cu" "*.Mask")
			(remove_unused_layers no)
			(net "GND")
			(clearance 0.1778)
			(thermal_gap 0.1778)
		)
		(pad "F4" thru_hole circle
			(at -0.999998 -0.700024 270)
			(size 0.8128 0.8128)
			(drill 0.399796)
			(layers "*.Cu" "*.Mask")
			(remove_unused_layers no)
			(net "TP_IOF4")
			(clearance 0.1524)
			(thermal_gap 0.1524)
		)
		(pad "F5" thru_hole circle
			(at 0.999998 -0.8001 270)
			(size 0.8636 0.8636)
			(drill 0.499872)
			(layers "*.Cu" "*.Mask")
			(remove_unused_layers no)
			(net "GND")
			(clearance 0.1778)
			(thermal_gap 0.1778)
		)
		(pad "F6" thru_hole circle
			(at 2.999994 -0.700024 270)
			(size 0.8128 0.8128)
			(drill 0.399796)
			(layers "*.Cu" "*.Mask")
			(remove_unused_layers no)
			(net "P3E_CPU1_PE3_MP_C_TXP<14>")
			(clearance 0.2921)
			(thermal_gap 0.2921)
		)
		(pad "F7" thru_hole circle
			(at 4.99999 -0.8001 270)
			(size 0.8636 0.8636)
			(drill 0.499872)
			(layers "*.Cu" "*.Mask")
			(remove_unused_layers no)
			(net "GND")
			(clearance 0.1778)
			(thermal_gap 0.1778)
		)
		(pad "F8" thru_hole circle
			(at 6.999986 -0.700024 270)
			(size 0.8128 0.8128)
			(drill 0.399796)
			(layers "*.Cu" "*.Mask")
			(remove_unused_layers no)
			(net "P3E_CPU1_PE3_MP_C_TXP<9>")
			(clearance 0.2921)
			(thermal_gap 0.2921)
		)
		(pad "G1" thru_hole circle
			(at -6.999986 -2.199894 270)
			(size 0.8128 0.8128)
			(drill 0.399796)
			(layers "*.Cu" "*.Mask")
			(remove_unused_layers no)
			(net "P3E_CPU1_PE3_MP_RXP<10>")
			(clearance 0.2921)
			(thermal_gap 0.2921)
		)
		(pad "G2" thru_hole circle
			(at -4.99999 -2.100072 270)
			(size 0.8636 0.8636)
			(drill 0.499872)
			(layers "*.Cu" "*.Mask")
			(remove_unused_layers no)
			(net "GND")
			(clearance 0.1778)
			(thermal_gap 0.1778)
		)
		(pad "G3" thru_hole circle
			(at -2.999994 -2.199894 270)
			(size 0.8128 0.8128)
			(drill 0.399796)
			(layers "*.Cu" "*.Mask")
			(remove_unused_layers no)
			(net "TP_IOG3")
			(clearance 0.1524)
			(thermal_gap 0.1524)
		)
		(pad "G4" thru_hole circle
			(at -0.999998 -2.100072 270)
			(size 0.8636 0.8636)
			(drill 0.499872)
			(layers "*.Cu" "*.Mask")
			(remove_unused_layers no)
			(net "GND")
			(clearance 0.1778)
			(thermal_gap 0.1778)
		)
		(pad "G5" thru_hole circle
			(at 0.999998 -2.199894 270)
			(size 0.8128 0.8128)
			(drill 0.399796)
			(layers "*.Cu" "*.Mask")
			(remove_unused_layers no)
			(net "FM_XRC_PRESENT_N")
			(clearance 0.1524)
			(thermal_gap 0.1524)
		)
		(pad "G6" thru_hole circle
			(at 2.999994 -2.100072 270)
			(size 0.8636 0.8636)
			(drill 0.499872)
			(layers "*.Cu" "*.Mask")
			(remove_unused_layers no)
			(net "GND")
			(clearance 0.1778)
			(thermal_gap 0.1778)
		)
		(pad "G7" thru_hole circle
			(at 4.99999 -2.199894 270)
			(size 0.8128 0.8128)
			(drill 0.399796)
			(layers "*.Cu" "*.Mask")
			(remove_unused_layers no)
			(net "P3E_CPU1_PE3_MP_C_TXN<13>")
			(clearance 0.2921)
			(thermal_gap 0.2921)
		)
		(pad "G8" thru_hole circle
			(at 6.999986 -2.100072 270)
			(size 0.8636 0.8636)
			(drill 0.499872)
			(layers "*.Cu" "*.Mask")
			(remove_unused_layers no)
			(net "GND")
			(clearance 0.1778)
			(thermal_gap 0.1778)
		)
		(pad "H1" thru_hole circle
			(at -6.999986 -3.599942 270)
			(size 0.8128 0.8128)
			(drill 0.399796)
			(layers "*.Cu" "*.Mask")
			(remove_unused_layers no)
			(net "P3E_CPU1_PE3_MP_RXN<10>")
			(clearance 0.2921)
			(thermal_gap 0.2921)
		)
		(pad "H2" thru_hole circle
			(at -4.99999 -3.50012 270)
			(size 0.8128 0.8128)
			(drill 0.399796)
			(layers "*.Cu" "*.Mask")
			(remove_unused_layers no)
			(net "P3E_CPU1_PE3_MP_RXP<13>")
			(clearance 0.2921)
			(thermal_gap 0.2921)
		)
		(pad "H3" thru_hole circle
			(at -2.999994 -3.599942 270)
			(size 0.8128 0.8128)
			(drill 0.399796)
			(layers "*.Cu" "*.Mask")
			(remove_unused_layers no)
			(net "TP_IOH3")
			(clearance 0.1524)
			(thermal_gap 0.1524)
		)
		(pad "H4" thru_hole circle
			(at -0.999998 -3.50012 270)
			(size 0.8128 0.8128)
			(drill 0.399796)
			(layers "*.Cu" "*.Mask")
			(remove_unused_layers no)
			(net "TP_IOH4")
			(clearance 0.2921)
			(thermal_gap 0.2921)
		)
		(pad "H5" thru_hole circle
			(at 0.999998 -3.599942 270)
			(size 0.8128 0.8128)
			(drill 0.399796)
			(layers "*.Cu" "*.Mask")
			(remove_unused_layers no)
			(net "FM_XRC_READY_N")
			(clearance 0.1524)
			(thermal_gap 0.1524)
		)
		(pad "H6" thru_hole circle
			(at 2.999994 -3.50012 270)
			(size 0.8128 0.8128)
			(drill 0.399796)
			(layers "*.Cu" "*.Mask")
			(remove_unused_layers no)
			(net "P3E_CPU1_PE3_MP_C_TXN<15>")
			(clearance 0.2921)
			(thermal_gap 0.2921)
		)
		(pad "H7" thru_hole circle
			(at 4.99999 -3.599942 270)
			(size 0.8128 0.8128)
			(drill 0.399796)
			(layers "*.Cu" "*.Mask")
			(remove_unused_layers no)
			(net "P3E_CPU1_PE3_MP_C_TXP<13>")
			(clearance 0.2921)
			(thermal_gap 0.2921)
		)
		(pad "H8" thru_hole circle
			(at 6.999986 -3.50012 270)
			(size 0.8128 0.8128)
			(drill 0.399796)
			(layers "*.Cu" "*.Mask")
			(remove_unused_layers no)
			(net "P3E_CPU1_PE3_MP_C_TXP<10>")
			(clearance 0.2921)
			(thermal_gap 0.2921)
		)
		(pad "I1" thru_hole circle
			(at -6.999986 -4.99999 270)
			(size 0.8636 0.8636)
			(drill 0.499872)
			(layers "*.Cu" "*.Mask")
			(remove_unused_layers no)
			(net "GND")
			(clearance 0.1778)
			(thermal_gap 0.1778)
		)
		(pad "I2" thru_hole circle
			(at -4.99999 -4.899914 270)
			(size 0.8128 0.8128)
			(drill 0.399796)
			(layers "*.Cu" "*.Mask")
			(remove_unused_layers no)
			(net "P3E_CPU1_PE3_MP_RXN<13>")
			(clearance 0.2921)
			(thermal_gap 0.2921)
		)
		(pad "I3" thru_hole circle
			(at -2.999994 -4.99999 270)
			(size 0.8636 0.8636)
			(drill 0.499872)
			(layers "*.Cu" "*.Mask")
			(remove_unused_layers no)
			(net "GND")
			(clearance 0.1778)
			(thermal_gap 0.1778)
		)
		(pad "I4" thru_hole circle
			(at -0.999998 -4.899914 270)
			(size 0.8128 0.8128)
			(drill 0.399796)
			(layers "*.Cu" "*.Mask")
			(remove_unused_layers no)
			(net "TP_IOI4")
			(clearance 0.2921)
			(thermal_gap 0.2921)
		)
		(pad "I5" thru_hole circle
			(at 0.999998 -4.99999 270)
			(size 0.8636 0.8636)
			(drill 0.499872)
			(layers "*.Cu" "*.Mask")
			(remove_unused_layers no)
			(net "GND")
			(clearance 0.1778)
			(thermal_gap 0.1778)
		)
		(pad "I6" thru_hole circle
			(at 2.999994 -4.899914 270)
			(size 0.8128 0.8128)
			(drill 0.399796)
			(layers "*.Cu" "*.Mask")
			(remove_unused_layers no)
			(net "P3E_CPU1_PE3_MP_C_TXP<15>")
			(clearance 0.2921)
			(thermal_gap 0.2921)
		)
		(pad "I7" thru_hole circle
			(at 4.99999 -4.99999 270)
			(size 0.8636 0.8636)
			(drill 0.499872)
			(layers "*.Cu" "*.Mask")
			(remove_unused_layers no)
			(net "GND")
			(clearance 0.1778)
			(thermal_gap 0.1778)
		)
		(pad "I8" thru_hole circle
			(at 6.999986 -4.899914 270)
			(size 0.8128 0.8128)
			(drill 0.399796)
			(layers "*.Cu" "*.Mask")
			(remove_unused_layers no)
			(net "P3E_CPU1_PE3_MP_C_TXN<10>")
			(clearance 0.2921)
			(thermal_gap 0.2921)
		)
	)
)
